(kicad_pcb
	(version 20260206)
	(generator "pcbnew")
	(generator_version "10.0")
	(general
		(thickness 1.6)
		(legacy_teardrops no)
	)
	(paper "A4")
	(title_block
		(title "01162023_DA0F0TEBIF0_F0T_Expander_BD_F_brd_V02_OCP.brd")
		(comment 1 "Grand Teton / footprints 93-99 of 9728")
	)
	(layers
		(0 "F.Cu" signal "TOP")
		(4 "In1.Cu" signal "GND")
		(6 "In2.Cu" signal "VCC")
		(8 "In3.Cu" signal "VCC1")
		(10 "In4.Cu" signal "GND1")
		(12 "In5.Cu" signal "IN1")
		(14 "In6.Cu" signal "GND2")
		(16 "In7.Cu" signal "IN2")
		(18 "In8.Cu" signal "GND3")
		(20 "In9.Cu" signal "IN3")
		(22 "In10.Cu" signal "GND4")
		(24 "In11.Cu" signal "IN4")
		(26 "In12.Cu" signal "GND5")
		(28 "In13.Cu" signal "IN5")
		(30 "In14.Cu" signal "GND6")
		(32 "In15.Cu" signal "IN6")
		(34 "In16.Cu" signal "GND7")
		(2 "B.Cu" signal "BOTTOM")
		(9 "F.Adhes" user "F.Adhesive")
		(11 "B.Adhes" user "B.Adhesive")
		(13 "F.Paste" user "Package Geometry/Pastemask Top")
		(15 "B.Paste" user "Package Geometry/Pastemask Bottom")
		(5 "F.SilkS" user "Ref Des/Silkscreen Top")
		(7 "B.SilkS" user "Ref Des/Silkscreen Bottom")
		(1 "F.Mask" user "Board Geometry/Soldermask Top")
		(3 "B.Mask" user "Board Geometry/Soldermask Bottom")
		(17 "Dwgs.User" user "User.Drawings")
		(19 "Cmts.User" user "User.Comments")
		(21 "Eco1.User" user "User.Eco1")
		(23 "Eco2.User" user "User.Eco2")
		(25 "Edge.Cuts" user "Board Geometry/Outline")
		(27 "Margin" user)
		(31 "F.CrtYd" user "Package Geometry/Place Bound Top")
		(29 "B.CrtYd" user "Package Geometry/Place Bound Bottom")
		(35 "F.Fab" user "Ref Des/Assembly Top")
		(33 "B.Fab" user "Ref Des/Assembly Bottom")
	)
	(footprint ""
		(layer "F.Cu")
		(at 299.40123 -55.78475 -90)
		(property "Reference" "PD114"
			(at 4.01955 2.21996 90)
			(unlocked yes)
			(layer "F.SilkS")
			(effects
				(font
					(size 0.7874 0.5842)
					(thickness 0.1524)
				)
				(justify left)
			)
		)
		(property "Value" ""
			(at 0 0 270)
			(layer "F.Fab")
			(effects
				(font
					(size 1.27 1.27)
				)
			)
		)
		(duplicate_pad_numbers_are_jumpers no)
		(fp_line
			(start -3.400044 1.459992)
			(end -3.400044 -1.459992)
			(stroke
				(width 0.1524)
				(type default)
			)
			(layer "F.SilkS")
		)
		(fp_line
			(start 4.107942 1.459992)
			(end -3.400044 1.459992)
			(stroke
				(width 0.1524)
				(type default)
			)
			(layer "F.SilkS")
		)
		(fp_line
			(start -3.400044 -1.459992)
			(end 4.107942 -1.459992)
			(stroke
				(width 0.1524)
				(type default)
			)
			(layer "F.SilkS")
		)
		(fp_line
			(start 4.107942 -1.459992)
			(end 4.107942 1.459992)
			(stroke
				(width 0.1524)
				(type default)
			)
			(layer "F.SilkS")
		)
		(fp_poly
			(pts
				(xy 4.107942 -1.459992) (xy 4.107942 1.459992) (xy 3.308096 1.459992) (xy 3.308096 -1.459992)
			)
			(stroke
				(width 0)
				(type default)
			)
			(fill yes)
			(layer "F.SilkS")
		)
		(fp_line
			(start -2.29997 1.459992)
			(end -2.29997 -1.459992)
			(stroke
				(width 0.1)
				(type default)
			)
			(layer "F.Fab")
		)
		(fp_line
			(start 2.29997 1.459992)
			(end -2.29997 1.459992)
			(stroke
				(width 0.1)
				(type default)
			)
			(layer "F.Fab")
		)
		(fp_line
			(start -2.29997 -1.459992)
			(end 2.29997 -1.459992)
			(stroke
				(width 0.1)
				(type default)
			)
			(layer "F.Fab")
		)
		(fp_line
			(start 2.29997 -1.459992)
			(end 2.29997 1.459992)
			(stroke
				(width 0.1)
				(type default)
			)
			(layer "F.Fab")
		)
		(fp_text user "-"
			(at 5.4102 0.29845 90)
			(unlocked yes)
			(layer "F.SilkS")
			(effects
				(font
					(size 1.905 1.4224)
					(thickness 0.1524)
				)
				(justify left)
			)
		)
		(fp_text user "+"
			(at -4.7752 -0.12065 270)
			(unlocked yes)
			(layer "F.SilkS")
			(effects
				(font
					(size 1.905 1.4224)
					(thickness 0.1524)
				)
				(justify left)
			)
		)
		(fp_text user "-"
			(at 5.4102 0.29845 90)
			(unlocked yes)
			(layer "F.Fab")
			(effects
				(font
					(size 1.905 1.4224)
					(thickness 0.1524)
				)
				(justify left)
			)
		)
		(fp_text user "+"
			(at -4.7752 -0.12065 270)
			(unlocked yes)
			(layer "F.Fab")
			(effects
				(font
					(size 1.905 1.4224)
					(thickness 0.1524)
				)
				(justify left)
			)
		)
		(pad "A" smd rect
			(at -1.999996 0)
			(size 1.7018 2.5146)
			(layers "F.Cu" "F.Mask" "F.Paste")
			(net "GND")
		)
		(pad "C" smd rect
			(at 1.999996 0)
			(size 1.7018 2.5146)
			(layers "F.Cu" "F.Mask" "F.Paste")
			(net "P12V_SSD10_R")
		)
	)
	(footprint ""
		(layer "F.Cu")
		(at 344.327988 -35.876738)
		(property "Reference" "R6106"
			(at 0 0 0)
			(layer "F.SilkS")
			(hide yes)
			(effects
				(font
					(size 1.27 1.27)
				)
			)
		)
		(property "Value" ""
			(at 0 0 0)
			(layer "F.Fab")
			(effects
				(font
					(size 1.27 1.27)
				)
			)
		)
		(duplicate_pad_numbers_are_jumpers no)
		(fp_line
			(start -0.7874 -0.4064)
			(end 0.7874 -0.4064)
			(stroke
				(width 0.1524)
				(type default)
			)
			(layer "F.SilkS")
		)
		(fp_line
			(start -0.7874 0.4064)
			(end -0.7874 -0.4064)
			(stroke
				(width 0.1524)
				(type default)
			)
			(layer "F.SilkS")
		)
		(fp_line
			(start 0.7874 -0.4064)
			(end 0.7874 0.4064)
			(stroke
				(width 0.1524)
				(type default)
			)
			(layer "F.SilkS")
		)
		(fp_line
			(start 0.7874 0.4064)
			(end -0.7874 0.4064)
			(stroke
				(width 0.1524)
				(type default)
			)
			(layer "F.SilkS")
		)
		(fp_line
			(start -0.67945 -0.305054)
			(end -0.12065 -0.305054)
			(stroke
				(width 0.1)
				(type default)
			)
			(layer "F.Fab")
		)
		(fp_line
			(start -0.67945 0.3048)
			(end -0.67945 -0.305054)
			(stroke
				(width 0.1)
				(type default)
			)
			(layer "F.Fab")
		)
		(fp_line
			(start -0.12065 -0.305054)
			(end -0.12065 -0.2794)
			(stroke
				(width 0.1)
				(type default)
			)
			(layer "F.Fab")
		)
		(fp_line
			(start -0.12065 -0.2794)
			(end 0.12065 -0.2794)
			(stroke
				(width 0.1)
				(type default)
			)
			(layer "F.Fab")
		)
		(fp_line
			(start -0.12065 0.2794)
			(end -0.12065 0.3048)
			(stroke
				(width 0.1)
				(type default)
			)
			(layer "F.Fab")
		)
		(fp_line
			(start -0.12065 0.3048)
			(end -0.67945 0.3048)
			(stroke
				(width 0.1)
				(type default)
			)
			(layer "F.Fab")
		)
		(fp_line
			(start 0.120396 0.2794)
			(end -0.12065 0.2794)
			(stroke
				(width 0.1)
				(type default)
			)
			(layer "F.Fab")
		)
		(fp_line
			(start 0.120396 0.3048)
			(end 0.120396 0.2794)
			(stroke
				(width 0.1)
				(type default)
			)
			(layer "F.Fab")
		)
		(fp_line
			(start 0.12065 -0.3048)
			(end 0.67945 -0.3048)
			(stroke
				(width 0.1)
				(type default)
			)
			(layer "F.Fab")
		)
		(fp_line
			(start 0.12065 -0.2794)
			(end 0.12065 -0.3048)
			(stroke
				(width 0.1)
				(type default)
			)
			(layer "F.Fab")
		)
		(fp_line
			(start 0.67945 -0.3048)
			(end 0.67945 0.3048)
			(stroke
				(width 0.1)
				(type default)
			)
			(layer "F.Fab")
		)
		(fp_line
			(start 0.67945 0.3048)
			(end 0.120396 0.3048)
			(stroke
				(width 0.1)
				(type default)
			)
			(layer "F.Fab")
		)
		(pad "1" smd circle
			(at -0.40005 0)
			(size 0 0)
			(layers "F.Cu" "F.Mask" "F.Paste")
			(net "PWRGD_P3V3_SSD12_D")
		)
		(pad "2" smd circle
			(at 0.40005 0)
			(size 0 0)
			(layers "F.Cu" "F.Mask" "F.Paste")
			(net "PWRGD_P3V3_SSD12_R")
		)
	)
	(footprint ""
		(layer "F.Cu")
		(at 201.203306 -59.571636 90)
		(property "Reference" "PR269"
			(at 0 0 90)
			(layer "F.SilkS")
			(hide yes)
			(effects
				(font
					(size 1.27 1.27)
				)
			)
		)
		(property "Value" ""
			(at 0 0 90)
			(layer "F.Fab")
			(effects
				(font
					(size 1.27 1.27)
				)
			)
		)
		(duplicate_pad_numbers_are_jumpers no)
		(fp_line
			(start 0.7874 -0.4064)
			(end 0.7874 0.4064)
			(stroke
				(width 0.1524)
				(type default)
			)
			(layer "F.SilkS")
		)
		(fp_line
			(start -0.7874 -0.4064)
			(end 0.7874 -0.4064)
			(stroke
				(width 0.1524)
				(type default)
			)
			(layer "F.SilkS")
		)
		(fp_line
			(start 0.7874 0.4064)
			(end -0.7874 0.4064)
			(stroke
				(width 0.1524)
				(type default)
			)
			(layer "F.SilkS")
		)
		(fp_line
			(start -0.7874 0.4064)
			(end -0.7874 -0.4064)
			(stroke
				(width 0.1524)
				(type default)
			)
			(layer "F.SilkS")
		)
		(fp_line
			(start -0.12065 -0.305054)
			(end -0.12065 -0.2794)
			(stroke
				(width 0.1)
				(type default)
			)
			(layer "F.Fab")
		)
		(fp_line
			(start -0.67945 -0.305054)
			(end -0.12065 -0.305054)
			(stroke
				(width 0.1)
				(type default)
			)
			(layer "F.Fab")
		)
		(fp_line
			(start 0.67945 -0.3048)
			(end 0.67945 0.3048)
			(stroke
				(width 0.1)
				(type default)
			)
			(layer "F.Fab")
		)
		(fp_line
			(start 0.12065 -0.3048)
			(end 0.67945 -0.3048)
			(stroke
				(width 0.1)
				(type default)
			)
			(layer "F.Fab")
		)
		(fp_line
			(start 0.12065 -0.2794)
			(end 0.12065 -0.3048)
			(stroke
				(width 0.1)
				(type default)
			)
			(layer "F.Fab")
		)
		(fp_line
			(start -0.12065 -0.2794)
			(end 0.12065 -0.2794)
			(stroke
				(width 0.1)
				(type default)
			)
			(layer "F.Fab")
		)
		(fp_line
			(start 0.120396 0.2794)
			(end -0.12065 0.2794)
			(stroke
				(width 0.1)
				(type default)
			)
			(layer "F.Fab")
		)
		(fp_line
			(start -0.12065 0.2794)
			(end -0.12065 0.3048)
			(stroke
				(width 0.1)
				(type default)
			)
			(layer "F.Fab")
		)
		(fp_line
			(start 0.67945 0.3048)
			(end 0.120396 0.3048)
			(stroke
				(width 0.1)
				(type default)
			)
			(layer "F.Fab")
		)
		(fp_line
			(start 0.120396 0.3048)
			(end 0.120396 0.2794)
			(stroke
				(width 0.1)
				(type default)
			)
			(layer "F.Fab")
		)
		(fp_line
			(start -0.12065 0.3048)
			(end -0.67945 0.3048)
			(stroke
				(width 0.1)
				(type default)
			)
			(layer "F.Fab")
		)
		(fp_line
			(start -0.67945 0.3048)
			(end -0.67945 -0.305054)
			(stroke
				(width 0.1)
				(type default)
			)
			(layer "F.Fab")
		)
		(pad "1" smd circle
			(at -0.40005 0 90)
			(size 0 0)
			(layers "F.Cu" "F.Mask" "F.Paste")
			(net "P3V3_SSD7_OCP")
		)
		(pad "2" smd circle
			(at 0.40005 0 90)
			(size 0 0)
			(layers "F.Cu" "F.Mask" "F.Paste")
			(net "GND")
		)
	)
	(footprint ""
		(layer "F.Cu")
		(at 20.174966 -48.753014 180)
		(property "Reference" "C201"
			(at 0 0 180)
			(layer "F.SilkS")
			(hide yes)
			(effects
				(font
					(size 1.27 1.27)
				)
			)
		)
		(property "Value" ""
			(at 0 0 180)
			(layer "F.Fab")
			(effects
				(font
					(size 1.27 1.27)
				)
			)
		)
		(duplicate_pad_numbers_are_jumpers no)
		(fp_line
			(start 0.7874 0.4064)
			(end -0.7874 0.4064)
			(stroke
				(width 0.1524)
				(type default)
			)
			(layer "F.SilkS")
		)
		(fp_line
			(start 0.7874 -0.4064)
			(end 0.7874 0.4064)
			(stroke
				(width 0.1524)
				(type default)
			)
			(layer "F.SilkS")
		)
		(fp_line
			(start -0.7874 0.4064)
			(end -0.7874 -0.4064)
			(stroke
				(width 0.1524)
				(type default)
			)
			(layer "F.SilkS")
		)
		(fp_line
			(start -0.7874 -0.4064)
			(end 0.7874 -0.4064)
			(stroke
				(width 0.1524)
				(type default)
			)
			(layer "F.SilkS")
		)
		(fp_line
			(start 0.67945 0.3048)
			(end 0.120396 0.3048)
			(stroke
				(width 0.1)
				(type default)
			)
			(layer "F.Fab")
		)
		(fp_line
			(start 0.67945 -0.3048)
			(end 0.67945 0.3048)
			(stroke
				(width 0.1)
				(type default)
			)
			(layer "F.Fab")
		)
		(fp_line
			(start 0.12065 -0.2794)
			(end 0.12065 -0.3048)
			(stroke
				(width 0.1)
				(type default)
			)
			(layer "F.Fab")
		)
		(fp_line
			(start 0.12065 -0.3048)
			(end 0.67945 -0.3048)
			(stroke
				(width 0.1)
				(type default)
			)
			(layer "F.Fab")
		)
		(fp_line
			(start 0.120396 0.3048)
			(end 0.120396 0.2794)
			(stroke
				(width 0.1)
				(type default)
			)
			(layer "F.Fab")
		)
		(fp_line
			(start 0.120396 0.2794)
			(end -0.12065 0.2794)
			(stroke
				(width 0.1)
				(type default)
			)
			(layer "F.Fab")
		)
		(fp_line
			(start -0.12065 0.3048)
			(end -0.67945 0.3048)
			(stroke
				(width 0.1)
				(type default)
			)
			(layer "F.Fab")
		)
		(fp_line
			(start -0.12065 0.2794)
			(end -0.12065 0.3048)
			(stroke
				(width 0.1)
				(type default)
			)
			(layer "F.Fab")
		)
		(fp_line
			(start -0.12065 -0.2794)
			(end 0.12065 -0.2794)
			(stroke
				(width 0.1)
				(type default)
			)
			(layer "F.Fab")
		)
		(fp_line
			(start -0.12065 -0.305054)
			(end -0.12065 -0.2794)
			(stroke
				(width 0.1)
				(type default)
			)
			(layer "F.Fab")
		)
		(fp_line
			(start -0.67945 0.3048)
			(end -0.67945 -0.305054)
			(stroke
				(width 0.1)
				(type default)
			)
			(layer "F.Fab")
		)
		(fp_line
			(start -0.67945 -0.305054)
			(end -0.12065 -0.305054)
			(stroke
				(width 0.1)
				(type default)
			)
			(layer "F.Fab")
		)
		(pad "1" smd circle
			(at -0.40005 0 180)
			(size 0 0)
			(layers "F.Cu" "F.Mask" "F.Paste")
			(net "P3V3_AUX")
		)
		(pad "2" smd circle
			(at 0.40005 0 180)
			(size 0 0)
			(layers "F.Cu" "F.Mask" "F.Paste")
			(net "GND")
		)
	)
	(footprint ""
		(layer "F.Cu")
		(at 387.580632 -107.403138)
		(property "Reference" "C689"
			(at 0 0 0)
			(layer "F.SilkS")
			(hide yes)
			(effects
				(font
					(size 1.27 1.27)
				)
			)
		)
		(property "Value" ""
			(at 0 0 0)
			(layer "F.Fab")
			(effects
				(font
					(size 1.27 1.27)
				)
			)
		)
		(duplicate_pad_numbers_are_jumpers no)
		(fp_line
			(start -0.299974 -0.150114)
			(end 0.299974 -0.150114)
			(stroke
				(width 0.1)
				(type default)
			)
			(layer "F.Fab")
		)
		(fp_line
			(start -0.299974 0.150114)
			(end -0.299974 -0.150114)
			(stroke
				(width 0.1)
				(type default)
			)
			(layer "F.Fab")
		)
		(fp_line
			(start 0.299974 -0.150114)
			(end 0.299974 0.150114)
			(stroke
				(width 0.1)
				(type default)
			)
			(layer "F.Fab")
		)
		(fp_line
			(start 0.299974 0.150114)
			(end -0.299974 0.150114)
			(stroke
				(width 0.1)
				(type default)
			)
			(layer "F.Fab")
		)
		(pad "1" smd rect
			(at -0.2667 0)
			(size 0.3048 0.381)
			(layers "F.Cu" "F.Mask" "F.Paste")
			(net "P5E_PEX3_STN1_TX_DN<20>")
		)
		(pad "2" smd rect
			(at 0.2667 0)
			(size 0.3048 0.381)
			(layers "F.Cu" "F.Mask" "F.Paste")
			(net "P5E_PEX3_STN1_TX_C_DN<20>")
		)
	)
	(footprint ""
		(layer "F.Cu")
		(at 322.22821 -300.64202 -90)
		(property "Reference" "R3970"
			(at 0 0 270)
			(layer "F.SilkS")
			(hide yes)
			(effects
				(font
					(size 1.27 1.27)
				)
			)
		)
		(property "Value" ""
			(at 0 0 270)
			(layer "F.Fab")
			(effects
				(font
					(size 1.27 1.27)
				)
			)
		)
		(duplicate_pad_numbers_are_jumpers no)
		(fp_line
			(start -0.7874 0.4064)
			(end -0.7874 -0.4064)
			(stroke
				(width 0.1524)
				(type default)
			)
			(layer "F.SilkS")
		)
		(fp_line
			(start 0.7874 0.4064)
			(end -0.7874 0.4064)
			(stroke
				(width 0.1524)
				(type default)
			)
			(layer "F.SilkS")
		)
		(fp_line
			(start -0.7874 -0.4064)
			(end 0.7874 -0.4064)
			(stroke
				(width 0.1524)
				(type default)
			)
			(layer "F.SilkS")
		)
		(fp_line
			(start 0.7874 -0.4064)
			(end 0.7874 0.4064)
			(stroke
				(width 0.1524)
				(type default)
			)
			(layer "F.SilkS")
		)
		(fp_line
			(start -0.67945 0.3048)
			(end -0.67945 -0.305054)
			(stroke
				(width 0.1)
				(type default)
			)
			(layer "F.Fab")
		)
		(fp_line
			(start -0.12065 0.3048)
			(end -0.67945 0.3048)
			(stroke
				(width 0.1)
				(type default)
			)
			(layer "F.Fab")
		)
		(fp_line
			(start 0.120396 0.3048)
			(end 0.120396 0.2794)
			(stroke
				(width 0.1)
				(type default)
			)
			(layer "F.Fab")
		)
		(fp_line
			(start 0.67945 0.3048)
			(end 0.120396 0.3048)
			(stroke
				(width 0.1)
				(type default)
			)
			(layer "F.Fab")
		)
		(fp_line
			(start -0.12065 0.2794)
			(end -0.12065 0.3048)
			(stroke
				(width 0.1)
				(type default)
			)
			(layer "F.Fab")
		)
		(fp_line
			(start 0.120396 0.2794)
			(end -0.12065 0.2794)
			(stroke
				(width 0.1)
				(type default)
			)
			(layer "F.Fab")
		)
		(fp_line
			(start -0.12065 -0.2794)
			(end 0.12065 -0.2794)
			(stroke
				(width 0.1)
				(type default)
			)
			(layer "F.Fab")
		)
		(fp_line
			(start 0.12065 -0.2794)
			(end 0.12065 -0.3048)
			(stroke
				(width 0.1)
				(type default)
			)
			(layer "F.Fab")
		)
		(fp_line
			(start 0.12065 -0.3048)
			(end 0.67945 -0.3048)
			(stroke
				(width 0.1)
				(type default)
			)
			(layer "F.Fab")
		)
		(fp_line
			(start 0.67945 -0.3048)
			(end 0.67945 0.3048)
			(stroke
				(width 0.1)
				(type default)
			)
			(layer "F.Fab")
		)
		(fp_line
			(start -0.67945 -0.305054)
			(end -0.12065 -0.305054)
			(stroke
				(width 0.1)
				(type default)
			)
			(layer "F.Fab")
		)
		(fp_line
			(start -0.12065 -0.305054)
			(end -0.12065 -0.2794)
			(stroke
				(width 0.1)
				(type default)
			)
			(layer "F.Fab")
		)
		(pad "1" smd circle
			(at -0.40005 0 270)
			(size 0 0)
			(layers "F.Cu" "F.Mask" "F.Paste")
			(net "I2C0_PEX2_SDA")
		)
		(pad "2" smd circle
			(at 0.40005 0 270)
			(size 0 0)
			(layers "F.Cu" "F.Mask" "F.Paste")
			(net "I2C_PEX2_HOST_SDA")
		)
	)
	(footprint ""
		(layer "F.Cu")
		(at 363.442758 -70.844918 -90)
		(property "Reference" "PD118"
			(at 4.093718 2.101088 90)
			(unlocked yes)
			(layer "F.SilkS")
			(effects
				(font
					(size 0.7874 0.5842)
					(thickness 0.1524)
				)
				(justify left)
			)
		)
		(property "Value" ""
			(at 0 0 270)
			(layer "F.Fab")
			(effects
				(font
					(size 1.27 1.27)
				)
			)
		)
		(duplicate_pad_numbers_are_jumpers no)
		(fp_line
			(start -3.400044 1.459992)
			(end -3.400044 -1.459992)
			(stroke
				(width 0.1524)
				(type default)
			)
			(layer "F.SilkS")
		)
		(fp_line
			(start 4.107942 1.459992)
			(end -3.400044 1.459992)
			(stroke
				(width 0.1524)
				(type default)
			)
			(layer "F.SilkS")
		)
		(fp_line
			(start -3.400044 -1.459992)
			(end 4.107942 -1.459992)
			(stroke
				(width 0.1524)
				(type default)
			)
			(layer "F.SilkS")
		)
		(fp_line
			(start 4.107942 -1.459992)
			(end 4.107942 1.459992)
			(stroke
				(width 0.1524)
				(type default)
			)
			(layer "F.SilkS")
		)
		(fp_poly
			(pts
				(xy 4.107942 -1.459992) (xy 4.107942 1.459992) (xy 3.308096 1.459992) (xy 3.308096 -1.459992)
			)
			(stroke
				(width 0)
				(type default)
			)
			(fill yes)
			(layer "F.SilkS")
		)
		(fp_line
			(start -2.29997 1.459992)
			(end -2.29997 -1.459992)
			(stroke
				(width 0.1)
				(type default)
			)
			(layer "F.Fab")
		)
		(fp_line
			(start 2.29997 1.459992)
			(end -2.29997 1.459992)
			(stroke
				(width 0.1)
				(type default)
			)
			(layer "F.Fab")
		)
		(fp_line
			(start -2.29997 -1.459992)
			(end 2.29997 -1.459992)
			(stroke
				(width 0.1)
				(type default)
			)
			(layer "F.Fab")
		)
		(fp_line
			(start 2.29997 -1.459992)
			(end 2.29997 1.459992)
			(stroke
				(width 0.1)
				(type default)
			)
			(layer "F.Fab")
		)
		(fp_text user "-"
			(at 5.4102 0.29845 90)
			(unlocked yes)
			(layer "F.SilkS")
			(effects
				(font
					(size 1.905 1.4224)
					(thickness 0.1524)
				)
				(justify left)
			)
		)
		(fp_text user "+"
			(at -5.16636 -0.171958 270)
			(unlocked yes)
			(layer "F.SilkS")
			(effects
				(font
					(size 1.905 1.4224)
					(thickness 0.1524)
				)
				(justify left)
			)
		)
		(fp_text user "-"
			(at 5.4102 0.29845 90)
			(unlocked yes)
			(layer "F.Fab")
			(effects
				(font
					(size 1.905 1.4224)
					(thickness 0.1524)
				)
				(justify left)
			)
		)
		(fp_text user "+"
			(at -4.7752 -0.12065 270)
			(unlocked yes)
			(layer "F.Fab")
			(effects
				(font
					(size 1.905 1.4224)
					(thickness 0.1524)
				)
				(justify left)
			)
		)
		(pad "A" smd rect
			(at -1.999996 0)
			(size 1.7018 2.5146)
			(layers "F.Cu" "F.Mask" "F.Paste")
			(net "GND")
		)
		(pad "C" smd rect
			(at 1.999996 0)
			(size 1.7018 2.5146)
			(layers "F.Cu" "F.Mask" "F.Paste")
			(net "P12V_SSD12_R")
		)
	)
)
